# S9S_MB_2U (Grand Teton) — schematic netlist excerpt (pin names and nets, part order shuffled) for the footprints in the layout excerpt that follows; sources: Cadence DE-HDL packaged netlist, KiCad conversion of 03242023_DA0F0TMBIJ0_F0T_Motherboard_J_brd_V01_OCP.brd

J4  SCONN288_ADR50017P087CC  SCONN288_ADR50017-P087CC IO  pkg DDR288S_1-1VXB  page 85
  VIN_BULK0  = P12V_S3_AUX_CPU0_NVDIMM
  RFU0  = TP_CHB_CPU0_DIMM2_FRU_0
  VIN_MGMT  = P3V3_AUX
  HSCL  = I3C_SPD_DDRABCD_CPU0_LVC1_SCL_3
  HSDA  = I3C_SPD_DDRABCD_CPU0_LVC1_SDA
  VSS0  = GND
  DQ0_A  = M_B_CPU0_SA_DQ<0>
  VSS1  = GND
  DQ1_A  = M_B_CPU0_SA_DQ<1>
  VSS2  = GND
  DQS0_A_T  = M_B_CPU0_SA_DQS_DP<0>
  DQS0_A_C  = M_B_CPU0_SA_DQS_DN<0>
  VSS3  = GND
  DQ4_A  = M_B_CPU0_SA_DQ<4>
  VSS4  = GND
  DQ5_A  = M_B_CPU0_SA_DQ<5>
  VSS5  = GND
  DQ8_A  = M_B_CPU0_SA_DQ<8>
  VSS6  = GND
  DQ9_A  = M_B_CPU0_SA_DQ<9>
  VSS7  = GND
  DQS1_A_T  = M_B_CPU0_SA_DQS_DP<1>
  DQS1_A_C  = M_B_CPU0_SA_DQS_DN<1>
  VSS8  = GND
  DQ12_A  = M_B_CPU0_SA_DQ<12>
  VSS9  = GND
  DQ13_A  = M_B_CPU0_SA_DQ<13>
  VSS10  = GND
  DQ16_A  = M_B_CPU0_SA_DQ<16>
  VSS11  = GND
  DQ17_A  = M_B_CPU0_SA_DQ<17>
  VSS12  = GND
  DQS2_A_T  = M_B_CPU0_SA_DQS_DP<2>
  DQS2_A_C  = M_B_CPU0_SA_DQS_DN<2>
  VSS13  = GND
  DQ20_A  = M_B_CPU0_SA_DQ<20>
  VSS14  = GND
  DQ21_A  = M_B_CPU0_SA_DQ<21>
  VSS15  = GND
  DQ24_A  = M_B_CPU0_SA_DQ<24>
  VSS16  = GND
  DQ25_A  = M_B_CPU0_SA_DQ<25>
  VSS17  = GND
  DQS3_A_T  = M_B_CPU0_SA_DQS_DP<3>
  DQS3_A_C  = M_B_CPU0_SA_DQS_DN<3>
  VSS18  = GND
  DQ28_A  = M_B_CPU0_SA_DQ<28>
  VSS19  = GND
  DQ29_A  = M_B_CPU0_SA_DQ<29>
  VSS20  = GND
  CB0_A  = M_B_CPU0_SA_CB<0>
  VSS21  = GND
  CB1_A  = M_B_CPU0_SA_CB<1>
  VSS22  = GND
  DQS4_A_T  = M_B_CPU0_SA_DQS_DP<4>
  DQS4_A_C  = M_B_CPU0_SA_DQS_DN<4>
  VSS23  = GND
  CB4_A  = M_B_CPU0_SA_CB<4>
  VSS24  = GND
  CB5_A  = M_B_CPU0_SA_CB<5>
  VSS25  = GND
  ALERT_N  = M_B_CPU0_ALERT_N
  VSS26  = GND
  CS0_A_N  = M_B_CPU0_SA_CS_N<2>
  VSS27  = GND
  CA0_A  = M_B_CPU0_SA_CA<0>
  VSS28  = GND
  CA2_A  = M_B_CPU0_SA_CA<2>
  VSS29  = GND
  CA4_A  = M_B_CPU0_SA_CA<4>
  VSS30  = GND
  CA6_A  = M_B_CPU0_SA_CA<6>
  VSS31  = GND
  PAR_A  = M_B_CPU0_SA_PAR
  VSS32  = GND
  CA0_B  = M_B_CPU0_SB_CA<0>
  VSS33  = GND
  CA2_B  = M_B_CPU0_SB_CA<2>
  VSS34  = GND
  CA4_B  = M_B_CPU0_SB_CA<4>
  VSS35  = GND
  CA6_B  = M_B_CPU0_SB_CA<6>
  VSS36  = GND
  CS0_B_N  = M_B_CPU0_SB_CS_N<2>
  VSS37  = GND
  \lbd||rsp_a_n\  = M_B_CPU0_SA_RSP<1>
  \lbs||rsp_b_n\  = M_B_CPU0_SB_RSP<1>
  VSS38  = GND
  CB4_B  = M_B_CPU0_SB_CB<4>
  VSS39  = GND
  CB5_B  = M_B_CPU0_SB_CB<5>
  VSS40  = GND
  \dqs9_b_t||tdqs9_b_t||dbi4_b_n\  = M_B_CPU0_SB_DQS_DP<9>
  \dqs9_b_c||tdqs9_b_c\  = M_B_CPU0_SB_DQS_DN<9>
  VSS41  = GND
  CB0_B  = M_B_CPU0_SB_CB<0>
  VSS42  = GND
  CB1_B  = M_B_CPU0_SB_CB<1>
  VSS43  = GND
  DQ0_B  = M_B_CPU0_SB_DQ<0>
  VSS44  = GND
  DQ1_B  = M_B_CPU0_SB_DQ<1>
  VSS45  = GND
  DQS0_B_T  = M_B_CPU0_SB_DQS_DP<0>
  DQS0_B_C  = M_B_CPU0_SB_DQS_DN<0>
  VSS46  = GND
  DQ4_B  = M_B_CPU0_SB_DQ<4>
  VSS47  = GND
  DQ5_B  = M_B_CPU0_SB_DQ<5>
  VSS48  = GND
  DQ8_B  = M_B_CPU0_SB_DQ<8>
  VSS49  = GND
  DQ9_B  = M_B_CPU0_SB_DQ<9>
  VSS50  = GND
  DQS1_B_T  = M_B_CPU0_SB_DQS_DP<1>
  DQS1_B_C  = M_B_CPU0_SB_DQS_DN<1>
  VSS51  = GND
  DQ12_B  = M_B_CPU0_SB_DQ<12>
  VSS52  = GND
  DQ13_B  = M_B_CPU0_SB_DQ<13>
  VSS53  = GND
  DQ16_B  = M_B_CPU0_SB_DQ<16>
  VSS54  = GND
  DQ17_B  = M_B_CPU0_SB_DQ<17>
  VSS55  = GND
  DQS2_B_T  = M_B_CPU0_SB_DQS_DP<2>
  DQS2_B_C  = M_B_CPU0_SB_DQS_DN<2>
  VSS56  = GND
  DQ20_B  = M_B_CPU0_SB_DQ<20>
  VSS57  = GND
  DQ21_B  = M_B_CPU0_SB_DQ<21>
  VSS58  = GND
  DQ24_B  = M_B_CPU0_SB_DQ<24>
  VSS59  = GND
  DQ25_B  = M_B_CPU0_SB_DQ<25>
  VSS60  = GND
  DQS3_B_T  = M_B_CPU0_SB_DQS_DP<3>
  DQS3_B_C  = M_B_CPU0_SB_DQS_DN<3>
  VSS61  = GND
  DQ28_B  = M_B_CPU0_SB_DQ<28>
  VSS62  = GND
  DQ29_B  = M_B_CPU0_SB_DQ<29>
  VSS63  = GND
  RFU1  = TP_CHB_CPU0_DIMM2_FRU_1
  VIN_BULK1  = P12V_S3_AUX_CPU0_NVDIMM
  VIN_BULK2  = P12V_S3_AUX_CPU0_NVDIMM
  \pwr_good||fail_n\  = PWRGD_CHB_CPU0_DIMM2
  HSA  = PD_CHB_CPU0_DIMM2_SAA
  RFU2  = TP_CHB_CPU0_DIMM2_FRU_2
  RFU3  = TP_CHB_CPU0_DIMM2_FRU_3
  VSS64  = GND
  DQ2_A  = M_B_CPU0_SA_DQ<2>
  VSS65  = GND
  DQ3_A  = M_B_CPU0_SA_DQ<3>
  VSS66  = GND
  \dqs5_a_c||tdqs5_a_c||dqs5_a_t||tdqs5_a_t\  = M_B_CPU0_SA_DQS_DN<5>
  \dqs5_a_t||tdqs5_a_t\  = M_B_CPU0_SA_DQS_DP<5>
  VSS67  = GND
  DQ6_A  = M_B_CPU0_SA_DQ<6>
  VSS68  = GND
  DQ7_A  = M_B_CPU0_SA_DQ<7>
  VSS69  = GND
  DQ10_A  = M_B_CPU0_SA_DQ<10>
  VSS70  = GND
  DQ11_A  = M_B_CPU0_SA_DQ<11>
  VSS71  = GND
  \dqs6_a_c||tdqs6_a_c||dqs6_a_t||tdqs6_a_t\  = M_B_CPU0_SA_DQS_DN<6>
  \dqs6_a_t||tdqs6_a_t\  = M_B_CPU0_SA_DQS_DP<6>
  VSS72  = GND
  DQ14_A  = M_B_CPU0_SA_DQ<14>
  VSS73  = GND
  DQ15_A  = M_B_CPU0_SA_DQ<15>
  VSS74  = GND
  DQ18_A  = M_B_CPU0_SA_DQ<18>
  VSS75  = GND
  DQ19_A  = M_B_CPU0_SA_DQ<19>
  VSS76  = GND
  \dqs7_a_c||tdqs7_a_c\  = M_B_CPU0_SA_DQS_DN<7>
  \dqs7_a_t||tdqs7_a_t\  = M_B_CPU0_SA_DQS_DP<7>
  VSS77  = GND
  DQ22_A  = M_B_CPU0_SA_DQ<22>
  VSS78  = GND
  DQ23_A  = M_B_CPU0_SA_DQ<23>
  VSS79  = GND
  DQ26_A  = M_B_CPU0_SA_DQ<26>
  VSS80  = GND
  DQ27_A  = M_B_CPU0_SA_DQ<27>
  VSS81  = GND
  \dqs8_a_c||tdqs8_a_c\  = M_B_CPU0_SA_DQS_DN<8>
  \dqs8_a_t||tdqs8_a_t\  = M_B_CPU0_SA_DQS_DP<8>
  VSS82  = GND
  DQ30_A  = M_B_CPU0_SA_DQ<30>
  VSS83  = GND
  DQ31_A  = M_B_CPU0_SA_DQ<31>
  VSS84  = GND
  CB2_A  = M_B_CPU0_SA_CB<2>
  VSS85  = GND
  CB3_A  = M_B_CPU0_SA_CB<3>
  VSS86  = GND
  \dqs9_a_c||tdqs9_a_c\  = M_B_CPU0_SA_DQS_DN<9>
  \dqs9_a_t||tdqs9_a_t\  = M_B_CPU0_SA_DQS_DP<9>
  VSS87  = GND
  CB6_A  = M_B_CPU0_SA_CB<6>
  VSS88  = GND
  CB7_A  = M_B_CPU0_SA_CB<7>
  VSS89  = GND
  RESET_N  = RST_M_AB_CPU0_FPGA_N
  VSS90  = GND
  CS1_A_N  = M_B_CPU0_SA_CS_N<3>
  VSS91  = GND
  CA1_A  = M_B_CPU0_SA_CA<1>
  VSS92  = GND
  CA3_A  = M_B_CPU0_SA_CA<3>
  VSS93  = GND
  CA5_A  = M_B_CPU0_SA_CA<5>
  VSS94  = GND
  CK_T  = M_B_CPU0_CLK_DP<1>
  CK_C  = M_B_CPU0_CLK_DN<1>
  VSS95  = GND
  RFU4  = TP_CHB_CPU0_DIMM2_FRU_4
  CA1_B  = M_B_CPU0_SB_CA<1>
  VSS96  = GND
  CA3_B  = M_B_CPU0_SB_CA<3>
  VSS97  = GND
  CA5_B  = M_B_CPU0_SB_CA<5>
  VSS98  = GND
  PAR_B  = M_B_CPU0_SB_PAR
  VSS99  = GND
  CS1_B_N  = M_B_CPU0_SB_CS_N<3>
  VSS100  = GND
  RFU5  = TP_CHB_CPU0_DIMM2_FRU_5
  RFU6  = TP_CHB_CPU0_DIMM2_FRU_6
  VSS101  = GND
  CB6_B  = M_B_CPU0_SB_CB<6>
  VSS102  = GND
  CB7_B  = M_B_CPU0_SB_CB<7>
  VSS103  = GND
  DQS4_B_C  = M_B_CPU0_SB_DQS_DN<4>
  DQS4_B_T  = M_B_CPU0_SB_DQS_DP<4>
  VSS104  = GND
  CB2_B  = M_B_CPU0_SB_CB<2>
  VSS105  = GND
  CB3_B  = M_B_CPU0_SB_CB<3>
  VSS106  = GND
  DQ2_B  = M_B_CPU0_SB_DQ<2>
  VSS107  = GND
  DQ3_B  = M_B_CPU0_SB_DQ<3>
  VSS108  = GND
  \dqs5_b_c||tdqs5_b_c\  = M_B_CPU0_SB_DQS_DN<5>
  \dqs5_b_t||tdqs5_b_t\  = M_B_CPU0_SB_DQS_DP<5>
  VSS109  = GND
  DQ6_B  = M_B_CPU0_SB_DQ<6>
  VSS110  = GND
  DQ7_B  = M_B_CPU0_SB_DQ<7>
  VSS111  = GND
  DQ10_B  = M_B_CPU0_SB_DQ<10>
  VSS112  = GND
  DQ11_B  = M_B_CPU0_SB_DQ<11>
  VSS113  = GND
  \dqs6_b_c||tdqs6_b_c\  = M_B_CPU0_SB_DQS_DN<6>
  \dqs6_b_t||tdqs6_b_t\  = M_B_CPU0_SB_DQS_DP<6>
  VSS114  = GND
  DQ14_B  = M_B_CPU0_SB_DQ<14>
  VSS115  = GND
  DQ15_B  = M_B_CPU0_SB_DQ<15>
  VSS116  = GND
  DQ18_B  = M_B_CPU0_SB_DQ<18>
  VSS117  = GND
  DQ19_B  = M_B_CPU0_SB_DQ<19>
  VSS118  = GND
  \dqs7_b_c||tdqs7_b_c\  = M_B_CPU0_SB_DQS_DN<7>
  \dqs7_b_t||tdqs7_b_t\  = M_B_CPU0_SB_DQS_DP<7>
  VSS119  = GND
  DQ22_B  = M_B_CPU0_SB_DQ<22>
  VSS120  = GND
  DQ23_B  = M_B_CPU0_SB_DQ<23>
  VSS121  = GND
  DQ26_B  = M_B_CPU0_SB_DQ<26>
  VSS122  = GND
  DQ27_B  = M_B_CPU0_SB_DQ<27>
  VSS123  = GND
  \dqs8_b_c||tdqs8_b_c\  = M_B_CPU0_SB_DQS_DN<8>
  \dqs8_b_t||tdqs8_b_t\  = M_B_CPU0_SB_DQS_DP<8>
  VSS124  = GND
  DQ30_B  = M_B_CPU0_SB_DQ<30>
  VSS125  = GND
  DQ31_B  = M_B_CPU0_SB_DQ<31>
  VSS126  = GND
  G1  = GND
  G2  = GND
  G3  = GND

(kicad_pcb
	(version 20260206)
	(generator "pcbnew")
	(generator_version "10.0")
	(general
		(thickness 1.6)
		(legacy_teardrops no)
	)
	(paper "A4")
	(title_block
		(title "03242023_DA0F0TMBIJ0_F0T_Motherboard_J_brd_V01_OCP.brd")
		(comment 1 "Grand Teton / footprint 1229 of 6105 (J4), pads 183-228 of 291")
	)
	(layers
		(0 "F.Cu" signal "TOP")
		(4 "In1.Cu" signal "GND")
		(6 "In2.Cu" signal "IN1")
		(8 "In3.Cu" signal "GND1")
		(10 "In4.Cu" signal "IN2")
		(12 "In5.Cu" signal "GND2")
		(14 "In6.Cu" signal "IN3")
		(16 "In7.Cu" signal "GND3")
		(18 "In8.Cu" signal "VCC")
		(20 "In9.Cu" signal "VCC1")
		(22 "In10.Cu" signal "GND4")
		(24 "In11.Cu" signal "IN4")
		(26 "In12.Cu" signal "GND5")
		(28 "In13.Cu" signal "IN5")
		(30 "In14.Cu" signal "GND6")
		(32 "In15.Cu" signal "IN6")
		(34 "In16.Cu" signal "GND7")
		(2 "B.Cu" signal "BOTTOM")
		(9 "F.Adhes" user "F.Adhesive")
		(11 "B.Adhes" user "B.Adhesive")
		(13 "F.Paste" user "Package Geometry/Pastemask Top")
		(15 "B.Paste" user "Package Geometry/Pastemask Bottom")
		(5 "F.SilkS" user "Ref Des/Silkscreen Top")
		(7 "B.SilkS" user "Ref Des/Silkscreen Bottom")
		(1 "F.Mask" user "Board Geometry/Soldermask Top")
		(3 "B.Mask" user "Board Geometry/Soldermask Bottom")
		(17 "Dwgs.User" user "User.Drawings")
		(19 "Cmts.User" user "User.Comments")
		(21 "Eco1.User" user "User.Eco1")
		(23 "Eco2.User" user "User.Eco2")
		(25 "Edge.Cuts" user "Board Geometry/Outline")
		(27 "Margin" user)
		(31 "F.CrtYd" user "Package Geometry/Place Bound Top")
		(29 "B.CrtYd" user "Package Geometry/Place Bound Bottom")
		(35 "F.Fab" user "Ref Des/Assembly Top")
		(33 "B.Fab" user "Ref Des/Assembly Bottom")
	)
	(footprint ""
		(layer "F.Cu")
		(at 295.849548 -258.091686)
		(property "Reference" "J4"
			(at -3.683 -81.702148 0)
			(unlocked yes)
			(layer "F.SilkS")
			(effects
				(font
					(size 0.7874 0.5842)
					(thickness 0.1524)
				)
				(justify left)
			)
		)
		(property "Value" ""
			(at 0 0 0)
			(layer "F.Fab")
			(effects
				(font
					(size 1.27 1.27)
				)
			)
		)
		(duplicate_pad_numbers_are_jumpers no)
		(pad "183" smd rect
			(at 2.050034 -31.025084 270)
			(size 0.519938 1.4986)
			(layers "F.Cu" "F.Mask" "F.Paste")
			(net "M_B_CPU0_SA_DQ<23>")
		)
		(pad "184" smd rect
			(at 2.050034 -30.174946 270)
			(size 0.519938 1.4986)
			(layers "F.Cu" "F.Mask" "F.Paste")
			(net "GND")
		)
		(pad "185" smd rect
			(at 2.050034 -29.325062 270)
			(size 0.519938 1.4986)
			(layers "F.Cu" "F.Mask" "F.Paste")
			(net "M_B_CPU0_SA_DQ<26>")
		)
		(pad "186" smd rect
			(at 2.050034 -28.474924 270)
			(size 0.519938 1.4986)
			(layers "F.Cu" "F.Mask" "F.Paste")
			(net "GND")
		)
		(pad "187" smd rect
			(at 2.050034 -27.62504 270)
			(size 0.519938 1.4986)
			(layers "F.Cu" "F.Mask" "F.Paste")
			(net "M_B_CPU0_SA_DQ<27>")
		)
		(pad "188" smd rect
			(at 2.050034 -26.774902 270)
			(size 0.519938 1.4986)
			(layers "F.Cu" "F.Mask" "F.Paste")
			(net "GND")
		)
		(pad "189" smd rect
			(at 2.050034 -25.925018 270)
			(size 0.519938 1.4986)
			(layers "F.Cu" "F.Mask" "F.Paste")
			(net "M_B_CPU0_SA_DQS_DN<8>")
		)
		(pad "190" smd rect
			(at 2.050034 -25.07488 270)
			(size 0.519938 1.4986)
			(layers "F.Cu" "F.Mask" "F.Paste")
			(net "M_B_CPU0_SA_DQS_DP<8>")
		)
		(pad "191" smd rect
			(at 2.050034 -24.224996 270)
			(size 0.519938 1.4986)
			(layers "F.Cu" "F.Mask" "F.Paste")
			(net "GND")
		)
		(pad "192" smd rect
			(at 2.050034 -23.375112 270)
			(size 0.519938 1.4986)
			(layers "F.Cu" "F.Mask" "F.Paste")
			(net "M_B_CPU0_SA_DQ<30>")
		)
		(pad "193" smd rect
			(at 2.050034 -22.524974 270)
			(size 0.519938 1.4986)
			(layers "F.Cu" "F.Mask" "F.Paste")
			(net "GND")
		)
		(pad "194" smd rect
			(at 2.050034 -21.67509 270)
			(size 0.519938 1.4986)
			(layers "F.Cu" "F.Mask" "F.Paste")
			(net "M_B_CPU0_SA_DQ<31>")
		)
		(pad "195" smd rect
			(at 2.050034 -20.824952 270)
			(size 0.519938 1.4986)
			(layers "F.Cu" "F.Mask" "F.Paste")
			(net "GND")
		)
		(pad "196" smd rect
			(at 2.050034 -19.975068 270)
			(size 0.519938 1.4986)
			(layers "F.Cu" "F.Mask" "F.Paste")
			(net "M_B_CPU0_SA_CB<2>")
		)
		(pad "197" smd rect
			(at 2.050034 -19.12493 270)
			(size 0.519938 1.4986)
			(layers "F.Cu" "F.Mask" "F.Paste")
			(net "GND")
		)
		(pad "198" smd rect
			(at 2.050034 -18.275046 270)
			(size 0.519938 1.4986)
			(layers "F.Cu" "F.Mask" "F.Paste")
			(net "M_B_CPU0_SA_CB<3>")
		)
		(pad "199" smd rect
			(at 2.050034 -17.424908 270)
			(size 0.519938 1.4986)
			(layers "F.Cu" "F.Mask" "F.Paste")
			(net "GND")
		)
		(pad "200" smd rect
			(at 2.050034 -16.575024 270)
			(size 0.519938 1.4986)
			(layers "F.Cu" "F.Mask" "F.Paste")
			(net "M_B_CPU0_SA_DQS_DN<9>")
		)
		(pad "201" smd rect
			(at 2.050034 -15.724886 270)
			(size 0.519938 1.4986)
			(layers "F.Cu" "F.Mask" "F.Paste")
			(net "M_B_CPU0_SA_DQS_DP<9>")
		)
		(pad "202" smd rect
			(at 2.050034 -14.875002 270)
			(size 0.519938 1.4986)
			(layers "F.Cu" "F.Mask" "F.Paste")
			(net "GND")
		)
		(pad "203" smd rect
			(at 2.050034 -14.025118 270)
			(size 0.519938 1.4986)
			(layers "F.Cu" "F.Mask" "F.Paste")
			(net "M_B_CPU0_SA_CB<6>")
		)
		(pad "204" smd rect
			(at 2.050034 -13.17498 270)
			(size 0.519938 1.4986)
			(layers "F.Cu" "F.Mask" "F.Paste")
			(net "GND")
		)
		(pad "205" smd rect
			(at 2.050034 -12.325096 270)
			(size 0.519938 1.4986)
			(layers "F.Cu" "F.Mask" "F.Paste")
			(net "M_B_CPU0_SA_CB<7>")
		)
		(pad "206" smd rect
			(at 2.050034 -11.474958 270)
			(size 0.519938 1.4986)
			(layers "F.Cu" "F.Mask" "F.Paste")
			(net "GND")
		)
		(pad "207" smd rect
			(at 2.050034 -10.625074 270)
			(size 0.519938 1.4986)
			(layers "F.Cu" "F.Mask" "F.Paste")
			(net "RST_M_AB_CPU0_FPGA_N")
		)
		(pad "208" smd rect
			(at 2.050034 -9.774936 270)
			(size 0.519938 1.4986)
			(layers "F.Cu" "F.Mask" "F.Paste")
			(net "GND")
		)
		(pad "209" smd rect
			(at 2.050034 -8.925052 270)
			(size 0.519938 1.4986)
			(layers "F.Cu" "F.Mask" "F.Paste")
			(net "M_B_CPU0_SA_CS_N<3>")
		)
		(pad "210" smd rect
			(at 2.050034 -8.074914 270)
			(size 0.519938 1.4986)
			(layers "F.Cu" "F.Mask" "F.Paste")
			(net "GND")
		)
		(pad "211" smd rect
			(at 2.050034 -7.22503 270)
			(size 0.519938 1.4986)
			(layers "F.Cu" "F.Mask" "F.Paste")
			(net "M_B_CPU0_SA_CA<1>")
		)
		(pad "212" smd rect
			(at 2.050034 -6.374892 270)
			(size 0.519938 1.4986)
			(layers "F.Cu" "F.Mask" "F.Paste")
			(net "GND")
		)
		(pad "213" smd rect
			(at 2.050034 -5.525008 270)
			(size 0.519938 1.4986)
			(layers "F.Cu" "F.Mask" "F.Paste")
			(net "M_B_CPU0_SA_CA<3>")
		)
		(pad "214" smd rect
			(at 2.050034 -4.675124 270)
			(size 0.519938 1.4986)
			(layers "F.Cu" "F.Mask" "F.Paste")
			(net "GND")
		)
		(pad "215" smd rect
			(at 2.050034 -3.824986 270)
			(size 0.519938 1.4986)
			(layers "F.Cu" "F.Mask" "F.Paste")
			(net "M_B_CPU0_SA_CA<5>")
		)
		(pad "216" smd rect
			(at 2.050034 -2.975102 270)
			(size 0.519938 1.4986)
			(layers "F.Cu" "F.Mask" "F.Paste")
			(net "GND")
		)
		(pad "217" smd rect
			(at 2.050034 -2.124964 270)
			(size 0.519938 1.4986)
			(layers "F.Cu" "F.Mask" "F.Paste")
			(net "M_B_CPU0_CLK_DP<1>")
		)
		(pad "218" smd rect
			(at 2.050034 -1.27508 270)
			(size 0.519938 1.4986)
			(layers "F.Cu" "F.Mask" "F.Paste")
			(net "M_B_CPU0_CLK_DN<1>")
		)
		(pad "219" smd rect
			(at 2.050034 -0.424942 270)
			(size 0.519938 1.4986)
			(layers "F.Cu" "F.Mask" "F.Paste")
			(net "GND")
		)
		(pad "220" smd rect
			(at 2.050034 5.525008 270)
			(size 0.519938 1.4986)
			(layers "F.Cu" "F.Mask" "F.Paste")
			(net "TP_CHB_CPU0_DIMM2_FRU_4")
		)
		(pad "221" smd rect
			(at 2.050034 6.374892 270)
			(size 0.519938 1.4986)
			(layers "F.Cu" "F.Mask" "F.Paste")
			(net "M_B_CPU0_SB_CA<1>")
		)
		(pad "222" smd rect
			(at 2.050034 7.22503 270)
			(size 0.519938 1.4986)
			(layers "F.Cu" "F.Mask" "F.Paste")
			(net "GND")
		)
		(pad "223" smd rect
			(at 2.050034 8.074914 270)
			(size 0.519938 1.4986)
			(layers "F.Cu" "F.Mask" "F.Paste")
			(net "M_B_CPU0_SB_CA<3>")
		)
		(pad "224" smd rect
			(at 2.050034 8.925052 270)
			(size 0.519938 1.4986)
			(layers "F.Cu" "F.Mask" "F.Paste")
			(net "GND")
		)
		(pad "225" smd rect
			(at 2.050034 9.774936 270)
			(size 0.519938 1.4986)
			(layers "F.Cu" "F.Mask" "F.Paste")
			(net "M_B_CPU0_SB_CA<5>")
		)
		(pad "226" smd rect
			(at 2.050034 10.625074 270)
			(size 0.519938 1.4986)
			(layers "F.Cu" "F.Mask" "F.Paste")
			(net "GND")
		)
		(pad "227" smd rect
			(at 2.050034 11.474958 270)
			(size 0.519938 1.4986)
			(layers "F.Cu" "F.Mask" "F.Paste")
			(net "M_B_CPU0_SB_PAR")
		)
		(pad "228" smd rect
			(at 2.050034 12.325096 270)
			(size 0.519938 1.4986)
			(layers "F.Cu" "F.Mask" "F.Paste")
			(net "GND")
		)
	)
)
